(kicad_pcb
	(version 20260206)
	(generator "pcbnew")
	(generator_version "10.0")
	(general
		(thickness 1.21888)
		(legacy_teardrops no)
	)
	(paper "A4")
	(title_block
		(title "timecard-proto-v0 — Timingcard_PCB.PcbDoc")
		(comment 1 "Time Appliance Project (Time Card) / footprints 1-14 of 167")
	)
	(layers
		(0 "F.Cu" signal "TOP")
		(4 "In1.Cu" signal "SGND")
		(6 "In2.Cu" signal "IN1")
		(8 "In3.Cu" signal "IN2")
		(10 "In4.Cu" signal "SGND1")
		(2 "B.Cu" signal "BOTTOM")
		(9 "F.Adhes" user "F.Adhesive")
		(11 "B.Adhes" user "B.Adhesive")
		(13 "F.Paste" user "Top Paste")
		(15 "B.Paste" user "Bottom Paste")
		(5 "F.SilkS" user "Top Overlay")
		(7 "B.SilkS" user "Bottom Overlay")
		(1 "F.Mask" user "Top Solder")
		(3 "B.Mask" user "Bottom Solder")
		(17 "Dwgs.User" user "User.Drawings")
		(19 "Cmts.User" user "User.Comments")
		(21 "Eco1.User" user "User.Eco1")
		(23 "Eco2.User" user "User.Eco2")
		(25 "Edge.Cuts" user)
		(27 "Margin" user)
		(31 "F.CrtYd" user "Top Courtyard")
		(29 "B.CrtYd" user "Bottom Courtyard")
		(35 "F.Fab" user "Top Component Center")
		(33 "B.Fab" user "Bottom Component Center")
	)
	(footprint "Resistors:RESC1608X50N"
		(layer "F.Cu")
		(at 163.640595 66.5716 180)
		(property "Reference" "R27"
			(at -1.948 -0.400345 0)
			(unlocked yes)
			(layer "F.SilkS")
			(effects
				(font
					(size 0.762 0.762)
					(thickness 0.2286)
				)
				(justify left bottom)
			)
		)
		(property "Value" "ERJ-3EKF1002V"
			(at 0.4445 -3.72999 0)
			(unlocked yes)
			(layer "F.SilkS")
			(hide yes)
			(effects
				(font
					(size 1.524 1.524)
					(thickness 0.254)
				)
				(justify left bottom)
			)
		)
		(sheetname "UART")
		(sheetfile "UART.kicad_sch")
		(duplicate_pad_numbers_are_jumpers no)
		(fp_line
			(start 0 -0.5)
			(end 0 0.5)
			(stroke
				(width 0.1524)
				(type solid)
			)
			(layer "F.SilkS")
		)
		(pad "1" smd rect
			(at -0.69 0 270)
			(size 1 0.72)
			(layers "F.Cu" "F.Mask" "F.Paste")
			(net "NetC54_2")
		)
		(pad "2" smd rect
			(at 0.69 0 270)
			(size 1 0.72)
			(layers "F.Cu" "F.Mask" "F.Paste")
			(net "NetR27_2")
		)
	)
	(footprint "Vault:CAPC1608X87X45ML20T05"
		(layer "F.Cu")
		(at 227.648595 119.6576)
		(property "Reference" "C15"
			(at 1.74 0.414345 0)
			(unlocked yes)
			(layer "F.SilkS")
			(effects
				(font
					(size 0.762 0.762)
					(thickness 0.2286)
				)
				(justify left bottom)
			)
		)
		(property "Value" "0.1uF"
			(at -1.1811 5.63499 0)
			(unlocked yes)
			(layer "F.SilkS")
			(hide yes)
			(effects
				(font
					(size 1.524 1.524)
					(thickness 0.254)
				)
				(justify left bottom)
			)
		)
		(sheetname "POWER")
		(sheetfile "POWER.kicad_sch")
		(duplicate_pad_numbers_are_jumpers no)
		(pad "1" smd rect
			(at -0.7 0 90)
			(size 1.1 1.05)
			(layers "F.Cu" "F.Mask" "F.Paste")
			(net "GND")
		)
		(pad "2" smd rect
			(at 0.7 0 90)
			(size 1.1 1.05)
			(layers "F.Cu" "F.Mask" "F.Paste")
			(net "+5.0V")
		)
	)
	(footprint "Vault:TECO-1909763-1_V"
		(layer "F.Cu")
		(at 75.088595 110.9786 90)
		(property "Reference" "J5"
			(at -2.926921 2.028605 0)
			(unlocked yes)
			(layer "F.SilkS")
			(effects
				(font
					(size 0.762 0.762)
					(thickness 0.2286)
				)
			)
		)
		(property "Value" "1909763-1"
			(at 4.608085 3.749802 90)
			(unlocked yes)
			(layer "F.SilkS")
			(hide yes)
			(effects
				(font
					(size 1.524 1.524)
					(thickness 0.254)
				)
			)
		)
		(sheetname "USER_IO")
		(sheetfile "USER_IO.kicad_sch")
		(duplicate_pad_numbers_are_jumpers no)
		(fp_line
			(start -0.55 -1.3)
			(end 0.55 -1.3)
			(stroke
				(width 0.2)
				(type solid)
			)
			(layer "F.SilkS")
		)
		(fp_circle
			(center -1.778 1.65)
			(end -1.653 1.65)
			(stroke
				(width 0.25)
				(type solid)
			)
			(fill no)
			(layer "F.SilkS")
		)
		(pad "1" smd rect
			(at -1.475 0 90)
			(size 1.05 2.2)
			(layers "F.Cu" "F.Mask" "F.Paste")
			(net "GND")
		)
		(pad "2" smd rect
			(at 0 1.525 90)
			(size 1 1.05)
			(layers "F.Cu" "F.Mask" "F.Paste")
			(net "ANT2")
		)
		(pad "3" smd rect
			(at 1.475 0 90)
			(size 1.05 2.2)
			(layers "F.Cu" "F.Mask" "F.Paste")
			(net "GND")
		)
	)
	(footprint "Vault:CAPC1608X87X45ML20T05"
		(layer "F.Cu")
		(at 168.593595 82.8276 -90)
		(property "Reference" "C81"
			(at -3.799 -2.113345 90)
			(unlocked yes)
			(layer "F.SilkS")
			(effects
				(font
					(size 0.762 0.762)
					(thickness 0.2286)
				)
				(justify left bottom)
			)
		)
		(property "Value" "0.1uF"
			(at 3.47599 0.2921 0)
			(unlocked yes)
			(layer "F.SilkS")
			(hide yes)
			(effects
				(font
					(size 1.524 1.524)
					(thickness 0.254)
				)
				(justify left bottom)
			)
		)
		(sheetname "MAC")
		(sheetfile "MAC.kicad_sch")
		(duplicate_pad_numbers_are_jumpers no)
		(pad "1" smd rect
			(at -0.7 0)
			(size 1.1 1.05)
			(layers "F.Cu" "F.Mask" "F.Paste")
			(net "GND")
		)
		(pad "2" smd rect
			(at 0.7 0)
			(size 1.1 1.05)
			(layers "F.Cu" "F.Mask" "F.Paste")
			(net "+3.3V_CLEAN")
		)
	)
	(footprint "Vault:CAPC1608X87X45ML20T05"
		(layer "F.Cu")
		(at 170.117595 82.8276 -90)
		(property "Reference" "C82"
			(at -3.674 -1.839345 90)
			(unlocked yes)
			(layer "F.SilkS")
			(effects
				(font
					(size 0.762 0.762)
					(thickness 0.2286)
				)
				(justify left bottom)
			)
		)
		(property "Value" "0.1uF"
			(at 3.47599 0.2921 0)
			(unlocked yes)
			(layer "F.SilkS")
			(hide yes)
			(effects
				(font
					(size 1.524 1.524)
					(thickness 0.254)
				)
				(justify left bottom)
			)
		)
		(sheetname "MAC")
		(sheetfile "MAC.kicad_sch")
		(duplicate_pad_numbers_are_jumpers no)
		(pad "1" smd rect
			(at -0.7 0)
			(size 1.1 1.05)
			(layers "F.Cu" "F.Mask" "F.Paste")
			(net "GND")
		)
		(pad "2" smd rect
			(at 0.7 0)
			(size 1.1 1.05)
			(layers "F.Cu" "F.Mask" "F.Paste")
			(net "+3.3V_CLEAN")
		)
	)
	(footprint "IntegratedCircuits:SOP64P600X170-16N"
		(layer "F.Cu")
		(at 157.036595 64.7936)
		(property "Reference" "U6"
			(at -0.97759 4.347655 0)
			(unlocked yes)
			(layer "F.SilkS")
			(effects
				(font
					(size 0.762 0.762)
					(thickness 0.2286)
				)
				(justify left bottom)
			)
		)
		(property "Value" "FT230XS-R"
			(at -3.4671 5.25399 0)
			(unlocked yes)
			(layer "F.SilkS")
			(hide yes)
			(effects
				(font
					(size 1.524 1.524)
					(thickness 0.254)
				)
				(justify left bottom)
			)
		)
		(sheetname "UART")
		(sheetfile "UART.kicad_sch")
		(duplicate_pad_numbers_are_jumpers no)
		(fp_line
			(start -1.6 -2.5)
			(end 1.6 -2.5)
			(stroke
				(width 0.2)
				(type solid)
			)
			(layer "F.SilkS")
		)
		(fp_line
			(start -1.6 2.5)
			(end -1.6 -2.5)
			(stroke
				(width 0.2)
				(type solid)
			)
			(layer "F.SilkS")
		)
		(fp_line
			(start -1.6 2.5)
			(end 1.6 2.5)
			(stroke
				(width 0.2)
				(type solid)
			)
			(layer "F.SilkS")
		)
		(fp_line
			(start 1.6 2.5)
			(end 1.6 -2.5)
			(stroke
				(width 0.2)
				(type solid)
			)
			(layer "F.SilkS")
		)
		(fp_circle
			(center -2.725 -2.9975)
			(end -2.725 -3.1225)
			(stroke
				(width 0.25)
				(type solid)
			)
			(fill no)
			(layer "F.SilkS")
		)
		(fp_circle
			(center -0.6 -1.5)
			(end -0.6 -1.8)
			(stroke
				(width 0.6)
				(type solid)
			)
			(fill no)
			(layer "F.SilkS")
		)
		(pad "1" smd oval
			(at -2.725 -2.2225 90)
			(size 0.45 1.45)
			(layers "F.Cu" "F.Mask" "F.Paste")
			(net "UART1_RXD")
		)
		(pad "2" smd oval
			(at -2.725 -1.5875 90)
			(size 0.45 1.45)
			(layers "F.Cu" "F.Mask" "F.Paste")
		)
		(pad "3" smd oval
			(at -2.725 -0.9525 90)
			(size 0.45 1.45)
			(layers "F.Cu" "F.Mask" "F.Paste")
			(net "NetU6_3")
		)
		(pad "4" smd oval
			(at -2.725 -0.3175 90)
			(size 0.45 1.45)
			(layers "F.Cu" "F.Mask" "F.Paste")
			(net "UART1_TXD")
		)
		(pad "5" smd oval
			(at -2.725 0.3175 90)
			(size 0.45 1.45)
			(layers "F.Cu" "F.Mask" "F.Paste")
			(net "GND")
		)
		(pad "6" smd oval
			(at -2.725 0.9525 90)
			(size 0.45 1.45)
			(layers "F.Cu" "F.Mask" "F.Paste")
		)
		(pad "7" smd oval
			(at -2.725 1.5875 90)
			(size 0.45 1.45)
			(layers "F.Cu" "F.Mask" "F.Paste")
		)
		(pad "8" smd oval
			(at -2.725 2.2225 90)
			(size 0.45 1.45)
			(layers "F.Cu" "F.Mask" "F.Paste")
			(net "NetJ3_3")
		)
		(pad "9" smd oval
			(at 2.725 2.2225 90)
			(size 0.45 1.45)
			(layers "F.Cu" "F.Mask" "F.Paste")
			(net "NetJ3_2")
		)
		(pad "10" smd oval
			(at 2.725 1.5875 90)
			(size 0.45 1.45)
			(layers "F.Cu" "F.Mask" "F.Paste")
			(net "NetU6_3")
		)
		(pad "11" smd oval
			(at 2.725 0.9525 90)
			(size 0.45 1.45)
			(layers "F.Cu" "F.Mask" "F.Paste")
			(net "NetR27_2")
		)
		(pad "12" smd oval
			(at 2.725 0.3175 90)
			(size 0.45 1.45)
			(layers "F.Cu" "F.Mask" "F.Paste")
			(net "NetC54_2")
		)
		(pad "13" smd oval
			(at 2.725 -0.3175 90)
			(size 0.45 1.45)
			(layers "F.Cu" "F.Mask" "F.Paste")
			(net "GND")
		)
		(pad "14" smd oval
			(at 2.725 -0.9525 90)
			(size 0.45 1.45)
			(layers "F.Cu" "F.Mask" "F.Paste")
		)
		(pad "15" smd oval
			(at 2.725 -1.5875 90)
			(size 0.45 1.45)
			(layers "F.Cu" "F.Mask" "F.Paste")
		)
		(pad "16" smd oval
			(at 2.725 -2.2225 90)
			(size 0.45 1.45)
			(layers "F.Cu" "F.Mask" "F.Paste")
		)
	)
	(footprint "Vault:CAPC1608X87X45ML20T05"
		(layer "F.Cu")
		(at 143.788595 90.3786 90)
		(property "Reference" "C23"
			(at -2.5714 0.026931 90)
			(unlocked yes)
			(layer "F.SilkS")
			(effects
				(font
					(size 0.762 0.762)
					(thickness 0.2286)
				)
			)
		)
		(property "Value" "0.1uF"
			(at 2.09443 2.657602 90)
			(unlocked yes)
			(layer "F.SilkS")
			(hide yes)
			(effects
				(font
					(size 1.524 1.524)
					(thickness 0.254)
				)
			)
		)
		(sheetname "GPS_IMU_SENSORS")
		(sheetfile "GPS_IMU_SENSORS.kicad_sch")
		(duplicate_pad_numbers_are_jumpers no)
		(pad "1" smd rect
			(at -0.7 0 180)
			(size 1.1 1.05)
			(layers "F.Cu" "F.Mask" "F.Paste")
			(net "GND")
		)
		(pad "2" smd rect
			(at 0.7 0 180)
			(size 1.1 1.05)
			(layers "F.Cu" "F.Mask" "F.Paste")
			(net "+3.3V_CLEAN")
		)
	)
	(footprint "Connectors:USB_1734035"
		(layer "F.Cu")
		(at 158.423595 58.3766 180)
		(property "Reference" "J3"
			(at -4.62041 5.313545 0)
			(unlocked yes)
			(layer "F.SilkS")
			(effects
				(font
					(size 0.762 0.762)
					(thickness 0.2286)
				)
				(justify left bottom)
			)
		)
		(property "Value" "USB_B_1734035"
			(at 3.0545 -5.81979 0)
			(unlocked yes)
			(layer "F.SilkS")
			(hide yes)
			(effects
				(font
					(size 1.524 1.524)
					(thickness 0.254)
				)
				(justify left bottom)
			)
		)
		(sheetname "UART")
		(sheetfile "UART.kicad_sch")
		(duplicate_pad_numbers_are_jumpers no)
		(fp_line
			(start 6.35 1.905)
			(end 6.35 3.81)
			(stroke
				(width 0.1524)
				(type solid)
			)
			(layer "F.SilkS")
		)
		(fp_line
			(start -3.175 1.905)
			(end -3.175 3.81)
			(stroke
				(width 0.1524)
				(type solid)
			)
			(layer "F.SilkS")
		)
		(fp_text user "1"
			(at -1.27 -1.08331 180)
			(unlocked yes)
			(layer "F.SilkS")
			(effects
				(font
					(size 1.524 1.524)
					(thickness 0.254)
				)
				(justify left bottom)
			)
		)
		(pad "" np_thru_hole circle
			(at -0.6 2.6 180)
			(size 0.8 0.8)
			(drill 0.9)
			(layers "*.Cu" "*.Mask")
			(thermal_bridge_angle 90)
		)
		(pad "" np_thru_hole circle
			(at 3.8 2.6 180)
			(size 0.8 0.8)
			(drill 0.9)
			(layers "*.Cu" "*.Mask")
			(thermal_bridge_angle 90)
		)
		(pad "0" smd rect
			(at -2.85 0.1 180)
			(size 2 2.5)
			(layers "F.Cu" "F.Mask" "F.Paste")
		)
		(pad "0" smd rect
			(at -2.85 5.6 180)
			(size 2 2.5)
			(layers "F.Cu" "F.Mask" "F.Paste")
		)
		(pad "0" smd rect
			(at 6.05 0.1 180)
			(size 2 2.5)
			(layers "F.Cu" "F.Mask" "F.Paste")
		)
		(pad "0" smd rect
			(at 6.05 5.6 180)
			(size 2 2.5)
			(layers "F.Cu" "F.Mask" "F.Paste")
		)
		(pad "1" smd rect
			(at 0 0 180)
			(size 0.5 2.3)
			(layers "F.Cu" "F.Mask" "F.Paste")
			(net "NetC54_2")
		)
		(pad "2" smd rect
			(at 0.8 0 180)
			(size 0.5 2.3)
			(layers "F.Cu" "F.Mask" "F.Paste")
			(net "NetJ3_2")
		)
		(pad "3" smd rect
			(at 1.6 0 180)
			(size 0.5 2.3)
			(layers "F.Cu" "F.Mask" "F.Paste")
			(net "NetJ3_3")
		)
		(pad "4" smd rect
			(at 2.4 0 180)
			(size 0.5 2.3)
			(layers "F.Cu" "F.Mask" "F.Paste")
		)
		(pad "5" smd rect
			(at 3.2 0 180)
			(size 0.5 2.3)
			(layers "F.Cu" "F.Mask" "F.Paste")
			(net "GND")
		)
	)
	(footprint "Vault:CAPC1608X87X45ML20T05"
		(layer "F.Cu")
		(at 164.275595 82.8276 -90)
		(property "Reference" "C78"
			(at -3.224 1.693655 90)
			(unlocked yes)
			(layer "F.SilkS")
			(effects
				(font
					(size 0.762 0.762)
					(thickness 0.2286)
				)
				(justify left bottom)
			)
		)
		(property "Value" "0.1uF"
			(at 3.47599 0.2921 0)
			(unlocked yes)
			(layer "F.SilkS")
			(hide yes)
			(effects
				(font
					(size 1.524 1.524)
					(thickness 0.254)
				)
				(justify left bottom)
			)
		)
		(sheetname "MAC")
		(sheetfile "MAC.kicad_sch")
		(duplicate_pad_numbers_are_jumpers no)
		(pad "1" smd rect
			(at -0.7 0)
			(size 1.1 1.05)
			(layers "F.Cu" "F.Mask" "F.Paste")
			(net "GND")
		)
		(pad "2" smd rect
			(at 0.7 0)
			(size 1.1 1.05)
			(layers "F.Cu" "F.Mask" "F.Paste")
			(net "+3.3V_CLEAN")
		)
	)
	(footprint "Capacitors:CAPC2012X14N"
		(layer "F.Cu")
		(at 152.312195 80.4908 90)
		(property "Reference" "C65"
			(at -5.2878 0.469745 90)
			(unlocked yes)
			(layer "F.SilkS")
			(effects
				(font
					(size 0.762 0.762)
					(thickness 0.2286)
				)
				(justify left bottom)
			)
		)
		(property "Value" "CAP_0805_1UF_50V"
			(at -3.52679 -1.5875 0)
			(unlocked yes)
			(layer "F.SilkS")
			(hide yes)
			(effects
				(font
					(size 1.524 1.524)
					(thickness 0.254)
				)
				(justify left bottom)
			)
		)
		(sheetname "MAC")
		(sheetfile "MAC.kicad_sch")
		(duplicate_pad_numbers_are_jumpers no)
		(fp_line
			(start -0.762 -0.9652)
			(end 0.762 -0.9652)
			(stroke
				(width 0.1524)
				(type solid)
			)
			(layer "F.SilkS")
		)
		(fp_line
			(start -0.762 0.9652)
			(end 0.762 0.9652)
			(stroke
				(width 0.1524)
				(type solid)
			)
			(layer "F.SilkS")
		)
		(pad "1" smd rect
			(at -0.9 0 180)
			(size 1.45 1.15)
			(layers "F.Cu" "F.Mask" "F.Paste")
			(net "GND")
		)
		(pad "2" smd rect
			(at 0.9 0 180)
			(size 1.45 1.15)
			(layers "F.Cu" "F.Mask" "F.Paste")
			(net "+3.3V_CLEAN")
		)
	)
	(footprint "Vault:CAPC1608X87X45ML20T05"
		(layer "F.Cu")
		(at 219.588595 94.3786 180)
		(property "Reference" "C11"
			(at 4.1 0.606655 0)
			(unlocked yes)
			(layer "F.SilkS")
			(effects
				(font
					(size 0.762 0.762)
					(thickness 0.2286)
				)
				(justify left bottom)
			)
		)
		(property "Value" "0.1uF"
			(at -11.3919 -1.69799 0)
			(unlocked yes)
			(layer "F.SilkS")
			(hide yes)
			(effects
				(font
					(size 1.524 1.524)
					(thickness 0.254)
				)
				(justify left bottom)
			)
		)
		(sheetname "POWER")
		(sheetfile "POWER.kicad_sch")
		(duplicate_pad_numbers_are_jumpers no)
		(pad "1" smd rect
			(at -0.7 0 270)
			(size 1.1 1.05)
			(layers "F.Cu" "F.Mask" "F.Paste")
			(net "GND")
		)
		(pad "2" smd rect
			(at 0.7 0 270)
			(size 1.1 1.05)
			(layers "F.Cu" "F.Mask" "F.Paste")
			(net "+3.3V")
		)
	)
	(footprint "Resistors:RESC1608X50N"
		(layer "F.Cu")
		(at 210.988595 100.5786 -90)
		(property "Reference" "R9"
			(at -2.427 -0.395345 90)
			(unlocked yes)
			(layer "F.SilkS")
			(effects
				(font
					(size 0.762 0.762)
					(thickness 0.2286)
				)
				(justify left bottom)
			)
		)
		(property "Value" "ERJ-3EKF2201V"
			(at -8.25881 -27.9527 0)
			(unlocked yes)
			(layer "F.SilkS")
			(hide yes)
			(effects
				(font
					(size 1.524 1.524)
					(thickness 0.254)
				)
				(justify left bottom)
			)
		)
		(sheetname "POWER")
		(sheetfile "POWER.kicad_sch")
		(duplicate_pad_numbers_are_jumpers no)
		(fp_line
			(start 0 0.5)
			(end 0 -0.5)
			(stroke
				(width 0.1524)
				(type solid)
			)
			(layer "F.SilkS")
		)
		(pad "1" smd rect
			(at -0.69 0)
			(size 1 0.72)
			(layers "F.Cu" "F.Mask" "F.Paste")
			(net "GND")
		)
		(pad "2" smd rect
			(at 0.69 0)
			(size 1 0.72)
			(layers "F.Cu" "F.Mask" "F.Paste")
			(net "NetC22_1")
		)
	)
	(footprint "Passives:DIOM6959X26N"
		(layer "F.Cu")
		(at 85.027595 97.5596 180)
		(property "Reference" "D16"
			(at 4.1402 4.097655 0)
			(unlocked yes)
			(layer "F.SilkS")
			(effects
				(font
					(size 0.762 0.762)
					(thickness 0.2286)
				)
				(justify left bottom)
			)
		)
		(property "Value" "SMCJ6.5CA"
			(at 4.2545 -5.91439 0)
			(unlocked yes)
			(layer "F.SilkS")
			(hide yes)
			(effects
				(font
					(size 1.524 1.524)
					(thickness 0.254)
				)
				(justify left bottom)
			)
		)
		(sheetname "USER_IO")
		(sheetfile "USER_IO.kicad_sch")
		(duplicate_pad_numbers_are_jumpers no)
		(fp_line
			(start 3.6 3.15)
			(end -3.6 3.15)
			(stroke
				(width 0.2)
				(type solid)
			)
			(layer "F.SilkS")
		)
		(fp_line
			(start 3.6 1.975)
			(end 3.6 3.15)
			(stroke
				(width 0.2)
				(type solid)
			)
			(layer "F.SilkS")
		)
		(fp_line
			(start 3.6 -3.15)
			(end 3.6 -1.975)
			(stroke
				(width 0.2)
				(type solid)
			)
			(layer "F.SilkS")
		)
		(fp_line
			(start 3.6 -3.15)
			(end -3.6 -3.15)
			(stroke
				(width 0.2)
				(type solid)
			)
			(layer "F.SilkS")
		)
		(fp_line
			(start -3.6 1.975)
			(end -3.6 3.15)
			(stroke
				(width 0.2)
				(type solid)
			)
			(layer "F.SilkS")
		)
		(fp_line
			(start -3.6 -3.15)
			(end -3.6 -1.975)
			(stroke
				(width 0.2)
				(type solid)
			)
			(layer "F.SilkS")
		)
		(fp_circle
			(center -4.25 -2.125)
			(end -4.25 -2)
			(stroke
				(width 0.25)
				(type solid)
			)
			(fill no)
			(layer "F.SilkS")
		)
		(pad "A" smd rect
			(at 2.85 0 270)
			(size 3.15 2.45)
			(layers "F.Cu" "F.Mask" "F.Paste")
			(net "ANT1")
		)
		(pad "K" smd rect
			(at -2.85 0 270)
			(size 3.15 2.45)
			(layers "F.Cu" "F.Mask" "F.Paste")
			(net "GND")
		)
	)
	(footprint "Capacitors:CAPC2012X14N"
		(layer "F.Cu")
		(at 166.053595 89.0506 90)
		(property "Reference" "C73"
			(at 2.00709 0.740865 90)
			(unlocked yes)
			(layer "F.SilkS")
			(effects
				(font
					(size 0.762 0.762)
					(thickness 0.2286)
				)
				(justify left bottom)
			)
		)
		(property "Value" "CAP_0805_22UF_16V"
			(at -3.52679 -1.5875 0)
			(unlocked yes)
			(layer "F.SilkS")
			(hide yes)
			(effects
				(font
					(size 1.524 1.524)
					(thickness 0.254)
				)
				(justify left bottom)
			)
		)
		(sheetname "MAC")
		(sheetfile "MAC.kicad_sch")
		(duplicate_pad_numbers_are_jumpers no)
		(fp_line
			(start -0.762 -0.9652)
			(end 0.762 -0.9652)
			(stroke
				(width 0.1524)
				(type solid)
			)
			(layer "F.SilkS")
		)
		(fp_line
			(start -0.762 0.9652)
			(end 0.762 0.9652)
			(stroke
				(width 0.1524)
				(type solid)
			)
			(layer "F.SilkS")
		)
		(pad "1" smd rect
			(at -0.9 0 180)
			(size 1.45 1.15)
			(layers "F.Cu" "F.Mask" "F.Paste")
			(net "GND")
		)
		(pad "2" smd rect
			(at 0.9 0 180)
			(size 1.45 1.15)
			(layers "F.Cu" "F.Mask" "F.Paste")
			(net "NetC72_2")
		)
	)
)
